(kicad_pcb
	(version 20241229)
	(generator "pcbnew")
	(generator_version "9.0")
	(general
		(thickness 1.61)
		(legacy_teardrops no)
	)
	(paper "A3")
	(title_block
		(title "RDIMM DDR5 Tester")
		(date "2026-05-21")
		(rev "2.2.0")
		(company "Antmicro")
		(comment 9 "footprints 48-52 of 796")
	)
	(layers
		(0 "F.Cu" signal)
		(4 "In1.Cu" power)
		(6 "In2.Cu" mixed)
		(8 "In3.Cu" power)
		(10 "In4.Cu" mixed)
		(12 "In5.Cu" power)
		(14 "In6.Cu" mixed)
		(16 "In7.Cu" power)
		(18 "In8.Cu" power)
		(20 "In9.Cu" mixed)
		(22 "In10.Cu" power)
		(2 "B.Cu" signal)
		(9 "F.Adhes" user "F.Adhesive")
		(11 "B.Adhes" user "B.Adhesive")
		(13 "F.Paste" user)
		(15 "B.Paste" user)
		(5 "F.SilkS" user "F.Silkscreen")
		(7 "B.SilkS" user "B.Silkscreen")
		(1 "F.Mask" user)
		(3 "B.Mask" user)
		(17 "Dwgs.User" user "User.Drawings")
		(19 "Cmts.User" user "User.Comments")
		(21 "Eco1.User" user "User.Eco1")
		(23 "Eco2.User" user "User.Eco2")
		(25 "Edge.Cuts" user)
		(27 "Margin" user)
		(31 "F.CrtYd" user "F.Courtyard")
		(29 "B.CrtYd" user "B.Courtyard")
		(35 "F.Fab" user)
		(33 "B.Fab" user)
	)
	(footprint "antmicro-footprints:C_0603_1608Metric"
		(layer "F.Cu")
		(at 257.6055 167.5)
		(descr "Capacitor SMD 0603")
		(tags "capacitor 0603")
		(property "Reference" "C189"
			(at 1.2945 0.55 0)
			(layer "F.SilkS")
			(effects
				(font
					(size 0.7 0.7)
					(thickness 0.15)
				)
				(justify left bottom)
			)
		)
		(property "Value" "C_22u_0603"
			(at -1.42757 1.770288 0)
			(layer "F.Fab")
			(effects
				(font
					(size 0.7 0.7)
					(thickness 0.15)
				)
				(justify left bottom)
			)
		)
		(property "Datasheet" "https://www.murata.com/products/productdetail?partno=GRM188R60J226MEA0%23"
			(at 0 0 0)
			(layer "F.Fab")
			(hide yes)
			(effects
				(font
					(size 1.27 1.27)
					(thickness 0.15)
				)
			)
		)
		(property "Manufacturer" "Murata"
			(at 0 0 0)
			(unlocked yes)
			(layer "F.Fab")
			(hide yes)
			(effects
				(font
					(size 1 1)
					(thickness 0.15)
				)
			)
		)
		(property "MPN" "GRM188R60J226MEA0D"
			(at 0 0 0)
			(unlocked yes)
			(layer "F.Fab")
			(hide yes)
			(effects
				(font
					(size 1 1)
					(thickness 0.15)
				)
			)
		)
		(property "Val" "22u"
			(at 0 0 0)
			(unlocked yes)
			(layer "F.Fab")
			(hide yes)
			(effects
				(font
					(size 1 1)
					(thickness 0.15)
				)
			)
		)
		(property "License" "Apache-2.0"
			(at 0 0 0)
			(unlocked yes)
			(layer "F.Fab")
			(hide yes)
			(effects
				(font
					(size 1 1)
					(thickness 0.15)
				)
			)
		)
		(property "Author" "Antmicro"
			(at 0 0 0)
			(unlocked yes)
			(layer "F.Fab")
			(hide yes)
			(effects
				(font
					(size 1 1)
					(thickness 0.15)
				)
			)
		)
		(property "Voltage" ""
			(at 0 0 0)
			(unlocked yes)
			(layer "F.Fab")
			(hide yes)
			(effects
				(font
					(size 1 1)
					(thickness 0.15)
				)
			)
		)
		(property "Dielectric" ""
			(at 0 0 0)
			(unlocked yes)
			(layer "F.Fab")
			(hide yes)
			(effects
				(font
					(size 1 1)
					(thickness 0.15)
				)
			)
		)
		(sheetname "/Supply/DC-DC AUX, MGT/")
		(sheetfile "dc-dc-aux-mgt.kicad_sch")
		(attr smd)
		(fp_line
			(start -0.15 -0.4)
			(end 0.15 -0.4)
			(stroke
				(width 0.15)
				(type solid)
			)
			(layer "F.SilkS")
		)
		(fp_line
			(start -0.15 0.4)
			(end 0.15 0.4)
			(stroke
				(width 0.15)
				(type solid)
			)
			(layer "F.SilkS")
		)
		(fp_rect
			(start -1.25 -0.65)
			(end 1.25 0.65)
			(stroke
				(width 0.05)
				(type solid)
			)
			(fill no)
			(layer "F.CrtYd")
		)
		(fp_rect
			(start -0.8 -0.4)
			(end 0.8 0.4)
			(stroke
				(width 0.15)
				(type solid)
			)
			(fill no)
			(layer "F.Fab")
		)
		(fp_text user "License: Apache-2.0"
			(at -1.682 5.895 0)
			(layer "F.Fab")
			(effects
				(font
					(size 0.7 0.7)
					(thickness 0.15)
				)
				(justify left bottom)
			)
		)
		(fp_text user "Author: Antmicro"
			(at -1.682 4.894 0)
			(layer "F.Fab")
			(effects
				(font
					(size 0.7 0.7)
					(thickness 0.15)
				)
				(justify left bottom)
			)
		)
		(fp_text user "${REFERENCE}"
			(at -1.682 3.895 0)
			(layer "F.Fab")
			(effects
				(font
					(size 0.7 0.7)
					(thickness 0.15)
				)
				(justify left bottom)
			)
		)
		(pad "1" smd roundrect
			(at -0.7 0)
			(size 0.8 1)
			(layers "F.Cu" "F.Mask" "F.Paste")
			(roundrect_rratio 0.2)
			(net 1 "GND")
			(pintype "passive")
		)
		(pad "2" smd roundrect
			(at 0.7 0)
			(size 0.8 1)
			(layers "F.Cu" "F.Mask" "F.Paste")
			(roundrect_rratio 0.2)
			(net 47 "/Supply/DC-DC AUX, MGT/MGTAVCC_local")
			(pintype "passive")
		)
	)
	(footprint "antmicro-footprints:LED_0603_1608Metric_G"
		(layer "F.Cu")
		(at 141.024499 185.549 90)
		(descr "LED SMD 0603 Green")
		(tags "LED SMD 0603 Green")
		(property "Reference" "D13"
			(at -0.001 -0.901 90)
			(layer "F.SilkS")
			(hide yes)
			(effects
				(font
					(size 0.7 0.7)
					(thickness 0.15)
				)
				(justify left bottom)
			)
		)
		(property "Value" "LED_G_0603_KP-1608CGCK"
			(at -0.001 1.599 90)
			(layer "F.Fab")
			(effects
				(font
					(size 0.7 0.7)
					(thickness 0.15)
				)
				(justify left bottom)
			)
		)
		(property "Datasheet" "http://www.kingbright.com/attachments/file/psearch//000/00/00/KP-1608CGCK(Ver.23B).pdf"
			(at 0 0 90)
			(layer "F.Fab")
			(hide yes)
			(effects
				(font
					(size 1.27 1.27)
					(thickness 0.15)
				)
			)
		)
		(property "MPN" "KP-1608CGCK"
			(at 0 0 90)
			(unlocked yes)
			(layer "F.Fab")
			(hide yes)
			(effects
				(font
					(size 1 1)
					(thickness 0.15)
				)
			)
		)
		(property "Manufacturer" "Kingbright"
			(at 0 0 90)
			(unlocked yes)
			(layer "F.Fab")
			(hide yes)
			(effects
				(font
					(size 1 1)
					(thickness 0.15)
				)
			)
		)
		(property "Color" "Green"
			(at 0 0 90)
			(unlocked yes)
			(layer "F.Fab")
			(hide yes)
			(effects
				(font
					(size 1 1)
					(thickness 0.15)
				)
			)
		)
		(property "Author" "Antmicro"
			(at 0 0 90)
			(unlocked yes)
			(layer "F.Fab")
			(hide yes)
			(effects
				(font
					(size 1 1)
					(thickness 0.15)
				)
			)
		)
		(property "License" "Apache-2.0"
			(at 0 0 90)
			(unlocked yes)
			(layer "F.Fab")
			(hide yes)
			(effects
				(font
					(size 1 1)
					(thickness 0.15)
				)
			)
		)
		(sheetname "/Debug FTDI + VNA/")
		(sheetfile "debug-ftdi.kicad_sch")
		(attr smd)
		(fp_line
			(start 0.22 -0.35)
			(end -0.22 -0.35)
			(stroke
				(width 0.15)
				(type solid)
			)
			(layer "F.SilkS")
		)
		(fp_line
			(start -1.18 -0.319)
			(end -1.18 0.321)
			(stroke
				(width 0.15)
				(type solid)
			)
			(layer "F.SilkS")
		)
		(fp_line
			(start 0.105328 0.001008)
			(end 0.24 0.001)
			(stroke
				(width 0.1)
				(type solid)
			)
			(layer "F.SilkS")
		)
		(fp_line
			(start -0.094672 0.001008)
			(end 0.105328 -0.198992)
			(stroke
				(width 0.1)
				(type solid)
			)
			(layer "F.SilkS")
		)
		(fp_line
			(start -0.094672 0.001008)
			(end -0.24 0.001008)
			(stroke
				(width 0.1)
				(type solid)
			)
			(layer "F.SilkS")
		)
		(fp_line
			(start 0.105328 0.201008)
			(end 0.105328 -0.198992)
			(stroke
				(width 0.1)
				(type solid)
			)
			(layer "F.SilkS")
		)
		(fp_line
			(start 0.105328 0.201008)
			(end -0.094672 0.001008)
			(stroke
				(width 0.1)
				(type solid)
			)
			(layer "F.SilkS")
		)
		(fp_line
			(start -0.094672 0.201008)
			(end -0.094672 -0.198992)
			(stroke
				(width 0.1)
				(type solid)
			)
			(layer "F.SilkS")
		)
		(fp_line
			(start 0.22 0.35)
			(end -0.22 0.35)
			(stroke
				(width 0.15)
				(type solid)
			)
			(layer "F.SilkS")
		)
		(fp_rect
			(start 1.25 0.65)
			(end -1.25 -0.65)
			(stroke
				(width 0.05)
				(type solid)
			)
			(fill no)
			(layer "F.CrtYd")
		)
		(fp_line
			(start 0.201 -0.202)
			(end -0.101 0)
			(stroke
				(width 0.15)
				(type solid)
			)
			(layer "F.Fab")
		)
		(fp_line
			(start -0.199 -0.202)
			(end -0.199 0.1)
			(stroke
				(width 0.15)
				(type solid)
			)
			(layer "F.Fab")
		)
		(fp_line
			(start 0.599 0)
			(end 0.201 0)
			(stroke
				(width 0.15)
				(type solid)
			)
			(layer "F.Fab")
		)
		(fp_line
			(start 0.201 0)
			(end 0.201 -0.202)
			(stroke
				(width 0.15)
				(type solid)
			)
			(layer "F.Fab")
		)
		(fp_line
			(start -0.101 0)
			(end 0.201 0.2)
			(stroke
				(width 0.15)
				(type solid)
			)
			(layer "F.Fab")
		)
		(fp_line
			(start -0.199 0)
			(end -0.597 0)
			(stroke
				(width 0.15)
				(type solid)
			)
			(layer "F.Fab")
		)
		(fp_line
			(start 0.201 0.2)
			(end 0.201 0)
			(stroke
				(width 0.15)
				(type solid)
			)
			(layer "F.Fab")
		)
		(fp_line
			(start -0.199 0.2)
			(end -0.199 0.1)
			(stroke
				(width 0.15)
				(type solid)
			)
			(layer "F.Fab")
		)
		(fp_rect
			(start 0.848 0.4)
			(end -0.85 -0.402)
			(stroke
				(width 0.15)
				(type solid)
			)
			(fill no)
			(layer "F.Fab")
		)
		(fp_text user "Author: Antmicro"
			(at -1.4224 4.799 90)
			(layer "F.Fab")
			(effects
				(font
					(size 0.7 0.7)
					(thickness 0.15)
				)
				(justify left bottom)
			)
		)
		(fp_text user "License: Apache-2.0"
			(at -1.4224 3.599 90)
			(layer "F.Fab")
			(effects
				(font
					(size 0.7 0.7)
					(thickness 0.15)
				)
				(justify left bottom)
			)
		)
		(fp_text user "${REFERENCE}"
			(at -1.4224 5.999 90)
			(layer "F.Fab")
			(effects
				(font
					(size 0.7 0.7)
					(thickness 0.15)
				)
				(justify left bottom)
			)
		)
		(pad "1" smd roundrect
			(at -0.7 0 270)
			(size 0.8 1)
			(layers "F.Cu" "F.Mask" "F.Paste")
			(roundrect_rratio 0.2)
			(net 1 "GND")
			(pinfunction "C")
			(pintype "passive")
		)
		(pad "2" smd roundrect
			(at 0.7 0 270)
			(size 0.8 1)
			(layers "F.Cu" "F.Mask" "F.Paste")
			(roundrect_rratio 0.2)
			(net 43 "Net-(D13-A)")
			(pinfunction "A")
			(pintype "passive")
		)
	)
	(footprint "antmicro-footprints:C_0603_1608Metric"
		(layer "F.Cu")
		(at 250.35 173.972 -90)
		(descr "Capacitor SMD 0603")
		(tags "capacitor 0603")
		(property "Reference" "C183"
			(at 1.328 -0.3 90)
			(layer "F.SilkS")
			(effects
				(font
					(size 0.7 0.7)
					(thickness 0.15)
				)
				(justify right bottom)
			)
		)
		(property "Value" "C_22u_0603"
			(at -1.42757 1.770288 90)
			(layer "F.Fab")
			(effects
				(font
					(size 0.7 0.7)
					(thickness 0.15)
				)
				(justify right bottom)
			)
		)
		(property "Datasheet" "https://www.murata.com/products/productdetail?partno=GRM188R60J226MEA0%23"
			(at 0 0 270)
			(layer "F.Fab")
			(hide yes)
			(effects
				(font
					(size 1.27 1.27)
					(thickness 0.15)
				)
			)
		)
		(property "Manufacturer" "Murata"
			(at 0 0 270)
			(unlocked yes)
			(layer "F.Fab")
			(hide yes)
			(effects
				(font
					(size 1 1)
					(thickness 0.15)
				)
			)
		)
		(property "MPN" "GRM188R60J226MEA0D"
			(at 0 0 270)
			(unlocked yes)
			(layer "F.Fab")
			(hide yes)
			(effects
				(font
					(size 1 1)
					(thickness 0.15)
				)
			)
		)
		(property "Val" "22u"
			(at 0 0 270)
			(unlocked yes)
			(layer "F.Fab")
			(hide yes)
			(effects
				(font
					(size 1 1)
					(thickness 0.15)
				)
			)
		)
		(property "License" "Apache-2.0"
			(at 0 0 270)
			(unlocked yes)
			(layer "F.Fab")
			(hide yes)
			(effects
				(font
					(size 1 1)
					(thickness 0.15)
				)
			)
		)
		(property "Author" "Antmicro"
			(at 0 0 270)
			(unlocked yes)
			(layer "F.Fab")
			(hide yes)
			(effects
				(font
					(size 1 1)
					(thickness 0.15)
				)
			)
		)
		(property "Voltage" ""
			(at 0 0 270)
			(unlocked yes)
			(layer "F.Fab")
			(hide yes)
			(effects
				(font
					(size 1 1)
					(thickness 0.15)
				)
			)
		)
		(property "Dielectric" ""
			(at 0 0 270)
			(unlocked yes)
			(layer "F.Fab")
			(hide yes)
			(effects
				(font
					(size 1 1)
					(thickness 0.15)
				)
			)
		)
		(sheetname "/Supply/DC-DC AUX, MGT/")
		(sheetfile "dc-dc-aux-mgt.kicad_sch")
		(attr smd)
		(fp_line
			(start -0.15 0.4)
			(end 0.15 0.4)
			(stroke
				(width 0.15)
				(type solid)
			)
			(layer "F.SilkS")
		)
		(fp_line
			(start -0.15 -0.4)
			(end 0.15 -0.4)
			(stroke
				(width 0.15)
				(type solid)
			)
			(layer "F.SilkS")
		)
		(fp_rect
			(start -1.25 -0.65)
			(end 1.25 0.65)
			(stroke
				(width 0.05)
				(type solid)
			)
			(fill no)
			(layer "F.CrtYd")
		)
		(fp_rect
			(start -0.8 -0.4)
			(end 0.8 0.4)
			(stroke
				(width 0.15)
				(type solid)
			)
			(fill no)
			(layer "F.Fab")
		)
		(fp_text user "License: Apache-2.0"
			(at -1.682 5.895 270)
			(layer "F.Fab")
			(effects
				(font
					(size 0.7 0.7)
					(thickness 0.15)
				)
				(justify left bottom)
			)
		)
		(fp_text user "Author: Antmicro"
			(at -1.682 4.894 270)
			(layer "F.Fab")
			(effects
				(font
					(size 0.7 0.7)
					(thickness 0.15)
				)
				(justify left bottom)
			)
		)
		(fp_text user "${REFERENCE}"
			(at -1.682 3.895 270)
			(layer "F.Fab")
			(effects
				(font
					(size 0.7 0.7)
					(thickness 0.15)
				)
				(justify left bottom)
			)
		)
		(pad "1" smd roundrect
			(at -0.7 0 270)
			(size 0.8 1)
			(layers "F.Cu" "F.Mask" "F.Paste")
			(roundrect_rratio 0.2)
			(net 1 "GND")
			(pintype "passive")
		)
		(pad "2" smd roundrect
			(at 0.7 0 270)
			(size 0.8 1)
			(layers "F.Cu" "F.Mask" "F.Paste")
			(roundrect_rratio 0.2)
			(net 37 "/Supply/DC-DC AUX, MGT/1V8_local")
			(pintype "passive")
		)
	)
	(footprint "antmicro-footprints:R_0402_1005Metric"
		(layer "F.Cu")
		(at 119.15 153.61 180)
		(descr "Resistor SMD 0402")
		(tags "resistor SMD 0402")
		(property "Reference" "R32"
			(at -5.11 -0.38 0)
			(layer "F.SilkS")
			(effects
				(font
					(size 0.7 0.7)
					(thickness 0.15)
				)
				(justify right bottom)
			)
		)
		(property "Value" "R_49k9_0402"
			(at -1.011843 1.772047 0)
			(layer "F.Fab")
			(effects
				(font
					(size 0.7 0.7)
					(thickness 0.15)
				)
				(justify right bottom)
			)
		)
		(property "Datasheet" "https://www.bourns.com/docs/product-datasheets/cr.pdf"
			(at 0 0 180)
			(layer "F.Fab")
			(hide yes)
			(effects
				(font
					(size 1.27 1.27)
					(thickness 0.15)
				)
			)
		)
		(property "MPN" "CR0402-FX-4992GLF"
			(at 0 0 180)
			(unlocked yes)
			(layer "F.Fab")
			(hide yes)
			(effects
				(font
					(size 1 1)
					(thickness 0.15)
				)
			)
		)
		(property "Manufacturer" "Bourns"
			(at 0 0 180)
			(unlocked yes)
			(layer "F.Fab")
			(hide yes)
			(effects
				(font
					(size 1 1)
					(thickness 0.15)
				)
			)
		)
		(property "License" "Apache-2.0"
			(at 0 0 180)
			(unlocked yes)
			(layer "F.Fab")
			(hide yes)
			(effects
				(font
					(size 1 1)
					(thickness 0.15)
				)
			)
		)
		(property "Author" "Antmicro"
			(at 0 0 180)
			(unlocked yes)
			(layer "F.Fab")
			(hide yes)
			(effects
				(font
					(size 1 1)
					(thickness 0.15)
				)
			)
		)
		(property "Val" "49k9"
			(at 0 0 180)
			(unlocked yes)
			(layer "F.Fab")
			(hide yes)
			(effects
				(font
					(size 1 1)
					(thickness 0.15)
				)
			)
		)
		(property "Tolerance" "1%"
			(at 0 0 180)
			(unlocked yes)
			(layer "F.Fab")
			(hide yes)
			(effects
				(font
					(size 1 1)
					(thickness 0.15)
				)
			)
		)
		(sheetname "/HDMI + SD Card/")
		(sheetfile "hdmi-sd-card.kicad_sch")
		(attr smd)
		(fp_rect
			(start -0.925 -0.47)
			(end 0.925 0.47)
			(stroke
				(width 0.05)
				(type default)
			)
			(fill no)
			(layer "F.CrtYd")
		)
		(fp_rect
			(start -0.5 -0.25)
			(end 0.5 0.25)
			(stroke
				(width 0.15)
				(type solid)
			)
			(fill no)
			(layer "F.Fab")
		)
		(fp_text user "${REFERENCE}"
			(at -0.95 3.168 180)
			(layer "F.Fab")
			(effects
				(font
					(size 0.7 0.7)
					(thickness 0.15)
				)
				(justify left bottom)
			)
		)
		(fp_text user "License: Apache-2.0"
			(at -0.95 5.169 180)
			(layer "F.Fab")
			(effects
				(font
					(size 0.7 0.7)
					(thickness 0.15)
				)
				(justify left bottom)
			)
		)
		(fp_text user "Author: Antmicro"
			(at -0.95 4.169 180)
			(layer "F.Fab")
			(effects
				(font
					(size 0.7 0.7)
					(thickness 0.15)
				)
				(justify left bottom)
			)
		)
		(pad "1" smd roundrect
			(at -0.48 0 180)
			(size 0.59 0.64)
			(layers "F.Cu" "F.Mask" "F.Paste")
			(roundrect_rratio 0.25)
			(net 678 "Net-(L8-Pad2)")
			(pintype "passive")
		)
		(pad "2" smd roundrect
			(at 0.48 0 180)
			(size 0.59 0.64)
			(layers "F.Cu" "F.Mask" "F.Paste")
			(roundrect_rratio 0.25)
			(net 322 "Net-(C300-Pad2)")
			(pintype "passive")
		)
	)
	(footprint "antmicro-footprints:C_0402_1005Metric"
		(layer "F.Cu")
		(at 136.124499 178.449 90)
		(descr "Capacitor SMD 0402")
		(tags "capacitor SMD 0402")
		(property "Reference" "C128"
			(at -1.051 -0.674499 90)
			(layer "F.SilkS")
			(effects
				(font
					(size 0.7 0.7)
					(thickness 0.15)
				)
				(justify left bottom)
			)
		)
		(property "Value" "C_100n_0402"
			(at -1.022927 2.155213 90)
			(layer "F.Fab")
			(effects
				(font
					(size 0.7 0.7)
					(thickness 0.15)
				)
				(justify left bottom)
			)
		)
		(property "Datasheet" "https://www.murata.com/products/productdetail?partno=GRM155R61H104KE14%23"
			(at 0 0 90)
			(layer "F.Fab")
			(hide yes)
			(effects
				(font
					(size 1.27 1.27)
					(thickness 0.15)
				)
			)
		)
		(property "MPN" "GRM155R61H104KE14D"
			(at 0 0 90)
			(unlocked yes)
			(layer "F.Fab")
			(hide yes)
			(effects
				(font
					(size 1 1)
					(thickness 0.15)
				)
			)
		)
		(property "Manufacturer" "Murata"
			(at 0 0 90)
			(unlocked yes)
			(layer "F.Fab")
			(hide yes)
			(effects
				(font
					(size 1 1)
					(thickness 0.15)
				)
			)
		)
		(property "License" "Apache-2.0"
			(at 0 0 90)
			(unlocked yes)
			(layer "F.Fab")
			(hide yes)
			(effects
				(font
					(size 1 1)
					(thickness 0.15)
				)
			)
		)
		(property "Author" "Antmicro"
			(at 0 0 90)
			(unlocked yes)
			(layer "F.Fab")
			(hide yes)
			(effects
				(font
					(size 1 1)
					(thickness 0.15)
				)
			)
		)
		(property "Val" "100n"
			(at 0 0 90)
			(unlocked yes)
			(layer "F.Fab")
			(hide yes)
			(effects
				(font
					(size 1 1)
					(thickness 0.15)
				)
			)
		)
		(property "Voltage" "50V"
			(at 0 0 90)
			(unlocked yes)
			(layer "F.Fab")
			(hide yes)
			(effects
				(font
					(size 1 1)
					(thickness 0.15)
				)
			)
		)
		(property "Dielectric" "X5R"
			(at 0 0 90)
			(unlocked yes)
			(layer "F.Fab")
			(hide yes)
			(effects
				(font
					(size 1 1)
					(thickness 0.15)
				)
			)
		)
		(sheetname "/Debug FTDI + VNA/")
		(sheetfile "debug-ftdi.kicad_sch")
		(attr smd)
		(fp_rect
			(start -0.925 -0.47)
			(end 0.925 0.47)
			(stroke
				(width 0.05)
				(type default)
			)
			(fill no)
			(layer "F.CrtYd")
		)
		(fp_line
			(start 0.504 -0.25)
			(end 0.504 0.248)
			(stroke
				(width 0.15)
				(type solid)
			)
			(layer "F.Fab")
		)
		(fp_line
			(start -0.494 -0.25)
			(end 0.504 -0.25)
			(stroke
				(width 0.15)
				(type solid)
			)
			(layer "F.Fab")
		)
		(fp_line
			(start 0.504 0.248)
			(end -0.494 0.248)
			(stroke
				(width 0.15)
				(type solid)
			)
			(layer "F.Fab")
		)
		(fp_line
			(start -0.494 0.248)
			(end -0.494 -0.25)
			(stroke
				(width 0.15)
				(type solid)
			)
			(layer "F.Fab")
		)
		(fp_text user "License: Apache-2.0"
			(at -0.939 5.799 90)
			(layer "F.Fab")
			(effects
				(font
					(size 0.7 0.7)
					(thickness 0.15)
				)
				(justify left bottom)
			)
		)
		(fp_text user "Author: Antmicro"
			(at -0.939 3.399 90)
			(layer "F.Fab")
			(effects
				(font
					(size 0.7 0.7)
					(thickness 0.15)
				)
				(justify left bottom)
			)
		)
		(fp_text user "${REFERENCE}"
			(at -0.939 4.599 90)
			(layer "F.Fab")
			(effects
				(font
					(size 0.7 0.7)
					(thickness 0.15)
				)
				(justify left bottom)
			)
		)
		(pad "1" smd roundrect
			(at -0.48 0 90)
			(size 0.59 0.64)
			(layers "F.Cu" "F.Mask" "F.Paste")
			(roundrect_rratio 0.25)
			(net 1 "GND")
			(pintype "passive")
		)
		(pad "2" smd roundrect
			(at 0.48 0 90)
			(size 0.59 0.64)
			(layers "F.Cu" "F.Mask" "F.Paste")
			(roundrect_rratio 0.25)
			(net 6 "/Debug FTDI + VNA/FTDI_3V3")
			(pintype "passive")
		)
	)
)
